# BASEBOARD_FAB2 (Tioga Pass) — schematic parts with pin connectivity, parts 4650–4650 of 4751; source: Cadence DE-HDL packaged netlist (pstxprt.dat, pstxnet.dat, pstchip.dat)

U2D1  SKX_EXT_B  IC  pkg BGA1  page 55  (pins 339-676 of 3647)
  AH53  VSS(822)  GROUND  = GND
  AH55  RSVD(231)  BI  = TP_CPU1_RSVD_231
  AH57  RSVD(230)  BI  = TP_CPU1_RSVD_230
  AH59  VSS(821)  GROUND  = GND
  AH61  VSS(820)  GROUND  = GND
  AH63  DDR2_CAVREF  OUT  = M_J_CPU_VREF
  AH65  VSS(819)  GROUND  = GND
  AH67  DDR0_DQS_DN(8)  BI  = M_G_DQS_DN<8>
  AH69  VSS(818)  GROUND  = GND
  AH71  RSVD(229)  BI  = TP_CPU1_RSVD_229
  AH73  RSVD(228)  BI  = TP_CPU1_RSVD_228
  AH75  VSS(817)  GROUND  = GND
  AH77  VSS(816)  GROUND  = GND
  AH79  DDR1_DQ(13)  BI  = M_H_DQ<13>
  AH81  DDR1_DQ(8)  BI  = M_H_DQ<8>
  AH83  VSS(815)  GROUND  = GND
  AH85  DDR0_DQS_DP(0)  BI  = M_G_DQS_DP<0>
  AJ2  UPI0_TX_DP(8)  OUT  = UPI_CPU1_CPU0_P0P0_DN<8>
  AJ4  VSS(1189)  GROUND  = GND
  AJ6  UPI0_RX_DN(6)  IN  = UPI_CPU0_CPU1_P0P0_DP<6>
  AJ8  VSS(814)  GROUND  = GND
  AJ10  BPM_N(0)  BI  = XDP_CPU_MBP0_N
  AJ12  ERROR_N(0)  OUT  = H_CPU1_ERR0_G_N
  AJ14  EAR_N  IN  = PD_CPU1_EAR_N
  AJ18  DDR012_SPDSCL  BI  = SMB_DDR_GHJ_SCL_G_R
  AJ20  RSVD(227)  BI  = TP_CPU1_RSVD_227
  AJ22  VSS(813)  GROUND  = GND
  AJ24  DDR2_DQS_DN(7)  BI  = M_J_DQS_DN<7>
  AJ26  VSS(812)  GROUND  = GND
  AJ28  VSS(811)  GROUND  = GND
  AJ30  DDR2_DQS_DN(6)  BI  = M_J_DQS_DN<6>
  AJ32  VSS(810)  GROUND  = GND
  AJ34  VSS(809)  GROUND  = GND
  AJ36  VCCIN(260)  POWER  = PVCCIN_CPU1
  AJ46  VSS(808)  GROUND  = GND
  AJ48  VSS(807)  GROUND  = GND
  AJ50  VSS(806)  GROUND  = GND
  AJ52  VSS(805)  GROUND  = GND
  AJ54  VSS(804)  GROUND  = GND
  AJ56  RSVD(226)  BI  = TP_CPU1_RSVD_226
  AJ58  RSVD(225)  BI  = TP_CPU1_RSVD_225
  AJ60  RSVD(224)  BI  = TP_CPU1_RSVD_224
  AJ62  RSVD(223)  BI  = TP_CPU1_RSVD_223
  AJ64  DDR0_CAVREF  OUT  = M_G_CPU_VREF
  AJ66  VSS(803)  GROUND  = GND
  AJ68  VSS(802)  GROUND  = GND
  AJ70  RSVD(222)  BI  = TP_CPU1_RSVD_222
  AJ74  VSS(801)  GROUND  = GND
  AJ76  DDR2_DQ(3)  BI  = M_J_DQ<3>
  AJ78  VSS(800)  GROUND  = GND
  AJ80  DDR1_DQ(12)  BI  = M_H_DQ<12>
  AJ82  VSS(799)  GROUND  = GND
  AJ84  DDR0_DQS_DN(0)  BI  = M_G_DQS_DN<0>
  AJ86  VSS(798)  GROUND  = GND
  AK1  UPI0_TX_DP(9)  OUT  = UPI_CPU1_CPU0_P0P0_DP<9>
  AK3  UPI0_TX_DP(10)  OUT  = UPI_CPU1_CPU0_P0P0_DN<10>
  AK5  UPI0_RX_DP(7)  IN  = UPI_CPU0_CPU1_P0P0_DN<7>
  AK7  UPI0_RX_DN(8)  IN  = UPI_CPU0_CPU1_P0P0_DP<8>
  AK9  VSS(797)  GROUND  = GND
  AK11  ERROR_N(1)  OUT  = H_CPU1_ERR1_G_N
  AK13  VSS(796)  GROUND  = GND
  AK19  VSS(795)  GROUND  = GND
  AK21  RSVD(221)  BI  = VSENSE_P1V8MCP_CPU1_SKT_VSEN
  AK23  VSS(794)  GROUND  = GND
  AK25  VSS(793)  GROUND  = GND
  AK27  RSVD(220)  BI  = CLK_322M_OSC_CPU1_RC_DP
  AK29  VSS(792)  GROUND  = GND
  AK31  VSS(791)  GROUND  = GND
  AK33  VSS(790)  GROUND  = GND
  AK35  VCCIN(259)  POWER  = PVCCIN_CPU1
  AK45  VCCIN(258)  POWER  = PVCCIN_CPU1
  AK47  VCCIN(257)  POWER  = PVCCIN_CPU1
  AK49  VCCIN(256)  POWER  = PVCCIN_CPU1
  AK51  VCCIN(255)  POWER  = PVCCIN_CPU1
  AK53  VCCIN(254)  POWER  = PVCCIN_CPU1
  AK55  VSS(789)  GROUND  = GND
  AK57  RSVD(219)  BI  = TP_CPU1_RSVD_219
  AK59  RSVD(218)  BI  = TP_CPU1_RSVD_218
  AK61  RSVD(217)  BI  = TP_CPU1_RSVD_217
  AK63  DDR1_CAVREF  OUT  = M_H_CPU_VREF
  AK65  VSS(788)  GROUND  = GND
  AK67  VSS(787)  GROUND  = GND
  AK69  RSVD(216)  BI  = TP_CPU1_RSVD_216
  AK73  VSS(786)  GROUND  = GND
  AK75  DDR2_DQ(7)  BI  = M_J_DQ<7>
  AK77  DDR2_DQ(2)  BI  = M_J_DQ<2>
  AK79  VSS(785)  GROUND  = GND
  AK81  VSS(784)  GROUND  = GND
  AK83  VSS(783)  GROUND  = GND
  AK85  VSS(782)  GROUND  = GND
  AL2  UPI0_TX_DN(9)  OUT  = UPI_CPU1_CPU0_P0P0_DN<9>
  AL4  VSS(781)  GROUND  = GND
  AL6  UPI0_RX_DN(7)  IN  = UPI_CPU0_CPU1_P0P0_DP<7>
  AL8  UPI0_RX_DP(9)  IN  = UPI_CPU0_CPU1_P0P0_DN<9>
  AL10  VSS(780)  GROUND  = GND
  AL12  ERROR_N(2)  OUT  = H_CPU1_ERR2_G_N
  AL14  CATERR_N  BI  = H_CPU1_CATERR_G_N
  AL18  PE_HP_SDA  BI  = SMB_CPU1_PE_HP_GTL_SDA
  AL20  RSVD(215)  BI  = VSENSE_P1V8MCP_CPU1_SKT_VRTN
  AL22  RSVD(214)  BI  = TP_CPU1_RSVD_214
  AL24  VSS(779)  GROUND  = GND
  AL26  RSVD(213)  BI  = CLK_322M_OSC_CPU1_RC_DN
  AL28  VCCIO(103)  POWER  = PVCCIO_CPU1
  AL30  VSS(778)  GROUND  = GND
  AL32  VSS(777)  GROUND  = GND
  AL34  VCCIN(253)  POWER  = PVCCIN_CPU1
  AL46  VCCIN(252)  POWER  = PVCCIN_CPU1
  AL48  VCCIN(251)  POWER  = PVCCIN_CPU1
  AL50  VCCIN(250)  POWER  = PVCCIN_CPU1
  AL52  VCCIN(249)  POWER  = PVCCIN_CPU1
  AL54  VCCIN(248)  POWER  = PVCCIN_CPU1
  AL56  VSS(776)  GROUND  = GND
  AL58  RSVD(212)  BI  = TP_CPU1_RSVD_212
  AL60  RSVD(211)  BI  = TP_CPU1_RSVD_211
  AL62  RSVD(210)  BI  = TP_CPU1_RSVD_210
  AL64  VSS(775)  GROUND  = GND
  AL66  DDR2_DQS_DN(12)  BI  = M_J_DQS_DN<12>
  AL68  VSS(774)  GROUND  = GND
  AL74  DDR2_DQS_DN(0)  BI  = M_J_DQS_DN<0>
  AL76  VSS(773)  GROUND  = GND
  AL78  VSS(772)  GROUND  = GND
  AL80  VSS(771)  GROUND  = GND
  AL82  VSS(770)  GROUND  = GND
  AL84  DDR0_DQS_DN(9)  BI  = M_G_DQS_DN<9>
  AL86  VSS(769)  GROUND  = GND
  AM1  VSS(768)  GROUND  = GND
  AM3  UPI0_TX_DN(10)  OUT  = UPI_CPU1_CPU0_P0P0_DP<10>
  AM5  VCCIO(4)  POWER  = PVCCIO_CPU1
  AM7  UPI0_RX_DP(8)  IN  = UPI_CPU0_CPU1_P0P0_DN<8>
  AM9  UPI0_RX_DN(9)  IN  = UPI_CPU0_CPU1_P0P0_DP<9>
  AM11  TSC_SYNC  BI  = PU_CPU1_TSC_SYNC
  AM13  TEST_3  BI  = TP_CPU1_RSVD_TEST_3
  AM19  PE_HP_SCL  BI  = SMB_CPU1_PE_HP_GTL_SCL
  AM21  RSVD(209)  BI  = PVCCMCP_CPU1
  AM23  RSVD(208)  BI  = TP_CPU1_RSVD_208
  AM25  RSVD(207)  BI  = PVCCMCP_CPU1
  AM27  RSVD(206)  BI  = CLK_100M_CPU1_RC_REFCLK0_DP
  AM29  VCCIO(102)  POWER  = PVCCIO_CPU1
  AM31  VSS(766)  GROUND  = GND
  AM33  VCCIN(247)  POWER  = PVCCIN_CPU1
  AM53  VCCIN(246)  POWER  = PVCCIN_CPU1
  AM55  VCCIN(245)  POWER  = PVCCIN_CPU1
  AM57  VSS(765)  GROUND  = GND
  AM59  RSVD(205)  BI  = TP_CPU1_RSVD_205
  AM61  RSVD(204)  BI  = TP_CPU1_RSVD_204
  AM63  VSS(764)  GROUND  = GND
  AM65  DDR2_DQ(30)  BI  = M_J_DQ<30>
  AM67  DDR2_DQ(24)  BI  = M_J_DQ<24>
  AM69  VSS(763)  GROUND  = GND
  AM73  VSS(762)  GROUND  = GND
  AM75  DDR2_DQS_DP(0)  BI  = M_J_DQS_DP<0>
  AM77  DDR2_DQ(6)  BI  = M_J_DQ<6>
  AM79  VSS(761)  GROUND  = GND
  AM81  DDR1_DQ(3)  BI  = M_H_DQ<3>
  AM83  VSS(760)  GROUND  = GND
  AM85  DDR0_DQS_DP(9)  BI  = M_G_DQS_DP<9>
  AN2  VSS(759)  GROUND  = GND
  AN4  UPI0_TX_DN(11)  OUT  = UPI_CPU1_CPU0_P0P0_DP<11>
  AN6  VSS(758)  GROUND  = GND
  AN8  UPI0_RX_DP(10)  IN  = UPI_CPU0_CPU1_P0P0_DP<10>
  AN10  VCCIO(40)  POWER  = PVCCIO_CPU1
  AN12  TEST_4  BI  = TP_CPU1_RSVD_TEST_4
  AN14  TEST_5  BI  = TP_CPU1_RSVD_TEST_5
  AN18  RSVD(203)  BI  = PVCCMCP_CPU1
  AN20  MSMI_N  BI  = H_CPU1_MSMI_G_N
  AN22  RSVD(202)  BI  = PVCCMCP_CPU1
  AN24  RSVD(201)  BI  = PVCCMCP_CPU1
  AN26  RSVD(200)  BI  = PVCCMCP_CPU1
  AN28  VSS(757)  GROUND  = GND
  AN30  DDR012_DRAM_PWR_OK  IN  = PWRGD_CPU1_DRAMPWROK_GHJ_G
  AN32  VCCIN(244)  POWER  = PVCCIN_CPU1
  AN54  VCCIN(243)  POWER  = PVCCIN_CPU1
  AN56  VCCIN(242)  POWER  = PVCCIN_CPU1
  AN58  VSS(756)  GROUND  = GND
  AN60  RSVD(199)  BI  = TP_CPU1_RSVD_199
  AN62  RSVD(198)  BI  = TP_CPU1_RSVD_198
  AN64  DDR2_DQ(26)  BI  = M_J_DQ<26>
  AN66  DDR2_DQS_DP(12)  BI  = M_J_DQS_DP<12>
  AN68  DDR2_DQ(28)  BI  = M_J_DQ<28>
  AN74  DDR2_DQ(1)  BI  = M_J_DQ<1>
  AN76  DDR2_DQS_DP(9)  BI  = M_J_DQS_DP<9>
  AN78  VSS(755)  GROUND  = GND
  AN80  DDR1_DQ(7)  BI  = M_H_DQ<7>
  AN82  DDR1_DQ(2)  BI  = M_H_DQ<2>
  AN84  DDR0_DQ(1)  BI  = M_G_DQ<1>
  AN86  DDR0_DQ(0)  BI  = M_G_DQ<0>
  AP1  UPI0_TX_DP(12)  OUT  = UPI_CPU1_CPU0_P0P0_DN<12>
  AP3  UPI0_TX_DP(11)  OUT  = UPI_CPU1_CPU0_P0P0_DN<11>
  AP5  VSS(754)  GROUND  = GND
  AP7  UPI0_RX_DN(10)  IN  = UPI_CPU0_CPU1_P0P0_DN<10>
  AP9  VSS(753)  GROUND  = GND
  AP11  NMI  IN  = TP_CPU1_NMI
  AP13  VSS(752)  GROUND  = GND
  AP17  PWR_DEBUG_N  IN  = XDP_CPU_PWR_DEBUG_N
  AP19  VSS(751)  GROUND  = GND
  AP21  RESET_N  IN  = RST_CPU1_G_N
  AP23  RSVD(197)  BI  = PVCCMCP_CPU1
  AP25  RSVD(196)  BI  = PVCCMCP_CPU1
  AP27  RSVD(195)  BI  = CLK_100M_CPU1_RC_REFCLK0_DN
  AP29  UPI01_RBIAS(1)  IN  = A_CPU1_UPI01_RBIAS
  AP31  VSS(750)  GROUND  = GND
  AP55  VCCIN(241)  POWER  = PVCCIN_CPU1
  AP57  VCCIN(240)  POWER  = PVCCIN_CPU1
  AP59  VSS(749)  GROUND  = GND
  AP61  RSVD(194)  BI  = TP_CPU1_RSVD_194
  AP63  VSS(748)  GROUND  = GND
  AP65  VSS(747)  GROUND  = GND
  AP67  VSS(746)  GROUND  = GND
  AP69  VSS(745)  GROUND  = GND
  AP73  VSS(744)  GROUND  = GND
  AP75  VSS(743)  GROUND  = GND
  AP77  DDR2_DQS_DN(9)  BI  = M_J_DQS_DN<9>
  AP79  DDR1_DQS_DN(0)  BI  = M_H_DQS_DN<0>
  AP81  VSS(742)  GROUND  = GND
  AP83  VSS(741)  GROUND  = GND
  AP85  VSS(740)  GROUND  = GND
  AR2  UPI0_TX_DP(13)  OUT  = UPI_CPU1_CPU0_P0P0_DN<13>
  AR4  UPI0_TX_DP(14)  OUT  = UPI_CPU1_CPU0_P0P0_DN<14>
  AR6  VSS(1190)  GROUND  = GND
  AR8  UPI0_RX_DN(11)  IN  = UPI_CPU0_CPU1_P0P0_DP<11>
  AR10  VSS(739)  GROUND  = GND
  AR12  PREQ_N  IN  = XDP_CPU_PREQ_N
  AR14  PMSYNC  IN  = H_PM_SYNC_GTL_R2
  AR16  TEST_6  BI  = TP_CPU1_TEST_6
  AR18  SAFE_MODE_BOOT  IN  = PU_CPU1_SAFE_MODE_BOOT
  AR20  RSVD(193)  BI  = PVCCMCP_CPU1
  AR22  RSVD(192)  BI  = PVCCMCP_CPU1
  AR24  VSS(738)  GROUND  = GND
  AR26  RSVD(191)  BI  = PVCCMCP_CPU1
  AR28  VCCIO(104)  POWER  = PVCCIO_CPU1
  AR30  VSS(737)  GROUND  = GND
  AR56  VCCIN(239)  POWER  = PVCCIN_CPU1
  AR58  VCCIN(238)  POWER  = PVCCIN_CPU1
  AR60  VSS(736)  GROUND  = GND
  AR62  RSVD(190)  BI  = TP_CPU1_RSVD_190
  AR64  DDR2_DQ(27)  BI  = M_J_DQ<27>
  AR66  DDR2_DQS_DP(3)  BI  = M_J_DQS_DP<3>
  AR68  DDR2_DQ(29)  BI  = M_J_DQ<29>
  AR72  VSS(735)  GROUND  = GND
  AR74  DDR2_DQ(5)  BI  = M_J_DQ<5>
  AR76  DDR2_DQ(0)  BI  = M_J_DQ<0>
  AR78  VSS(734)  GROUND  = GND
  AR80  DDR1_DQS_DP(0)  BI  = M_H_DQS_DP<0>
  AR82  DDR1_DQ(6)  BI  = M_H_DQ<6>
  AR84  DDR0_DQ(5)  BI  = M_G_DQ<5>
  AR86  DDR0_DQ(4)  BI  = M_G_DQ<4>
  AT1  UPI0_TX_DN(12)  OUT  = UPI_CPU1_CPU0_P0P0_DP<12>
  AT3  UPI0_TX_DN(13)  OUT  = UPI_CPU1_CPU0_P0P0_DP<13>
  AT5  VCCIO(5)  POWER  = PVCCIO_CPU1
  AT7  VCCIO(6)  POWER  = PVCCIO_CPU1
  AT9  UPI0_RX_DP(12)  IN  = UPI_CPU0_CPU1_P0P0_DP<12>
  AT11  VCCIO(38)  POWER  = PVCCIO_CPU1
  AT13  RSVD(189)  BI  = TP_CPU1_RSVD_189
  AT15  VSS(731)  GROUND  = GND
  AT17  VSS(730)  GROUND  = GND
  AT19  PMSYNC_CLK  IN  = H_PMSYNC_CLK_24M_CPU1
  AT21  VSS(729)  GROUND  = GND
  AT23  RSVD(188)  BI  = PVCCMCP_CPU1
  AT25  RSVD(187)  BI  = PVCCMCP_CPU1
  AT27  VSS(728)  GROUND  = GND
  AT29  UPI01_RBIAS(0)  IN  = A_CPU1_UPI01_RBIAS
  AT57  VCCIN(237)  POWER  = PVCCIN_CPU1
  AT59  VCCIN(236)  POWER  = PVCCIN_CPU1
  AT61  VSS(727)  GROUND  = GND
  AT63  VSS(726)  GROUND  = GND
  AT65  DDR2_DQ(31)  BI  = M_J_DQ<31>
  AT67  DDR2_DQ(25)  BI  = M_J_DQ<25>
  AT69  VSS(725)  GROUND  = GND
  AT71  DDR2_DQS_DN(17)  BI  = M_J_DQS_DN<17>
  AT73  VSS(724)  GROUND  = GND
  AT75  DDR2_DQ(4)  BI  = M_J_DQ<4>
  AT77  VSS(723)  GROUND  = GND
  AT79  DDR1_DQ(1)  BI  = M_H_DQ<1>
  AT81  DDR1_DQS_DP(9)  BI  = M_H_DQS_DP<9>
  AT83  VSS(722)  GROUND  = GND
  AT85  VSS(721)  GROUND  = GND
  AU2  VSS(720)  GROUND  = GND
  AU4  UPI0_TX_DN(14)  OUT  = UPI_CPU1_CPU0_P0P0_DP<14>
  AU6  VSS(719)  GROUND  = GND
  AU8  UPI0_RX_DP(11)  IN  = UPI_CPU0_CPU1_P0P0_DN<11>
  AU10  UPI0_RX_DN(12)  IN  = UPI_CPU0_CPU1_P0P0_DN<12>
  AU12  PECI  BI  = PECI_CPU_G
  AU14  FIVR_FAULT  OUT  = H_CPU1_FIVR_FAULT_G
  AU16  SOCKET_ID(1)  IN  = PU_CPU1_SOCKET_ID_1
  AU18  TEST_7  BI  = TP_CPU1_TEST_7
  AU20  SOCKET_ID(2)  IN  = TP_CPU1_SOCKET_ID_2
  AU22  SOCKET_ID(0)  IN  = PU_CPU1_SOCKET_ID_0
  AU24  BCLK0_DN  IN  = CLK_100M_CPU1_BCLK0_DN
  AU26  VSS(718)  GROUND  = GND
  AU28  VSS(717)  GROUND  = GND
  AU58  VCCIN(235)  POWER  = PVCCIN_CPU1
  AU60  VCCIN(234)  POWER  = PVCCIN_CPU1
  AU62  VSS(716)  GROUND  = GND
  AU64  VSS(715)  GROUND  = GND
  AU66  DDR2_DQS_DN(3)  BI  = M_J_DQS_DN<3>
  AU68  VSS(714)  GROUND  = GND
  AU70  DDR2_ECC(6)  BI  = M_J_ECC<6>
  AU72  DDR2_ECC(0)  BI  = M_J_ECC<0>
  AU74  VSS(713)  GROUND  = GND
  AU76  VSS(712)  GROUND  = GND
  AU78  VSS(711)  GROUND  = GND
  AU80  VSS(710)  GROUND  = GND
  AU82  DDR1_DQS_DN(9)  BI  = M_H_DQS_DN<9>
  AU84  VSS(709)  GROUND  = GND
  AU86  VSS(708)  GROUND  = GND
  AV1  VSS(707)  GROUND  = GND
  AV3  VSS(706)  GROUND  = GND
  AV5  UPI0_TX_DN(15)  OUT  = UPI_CPU1_CPU0_P0P0_DP<15>
  AV7  VSS(705)  GROUND  = GND
  AV9  UPI0_RX_DP(16)  IN  = UPI_CPU0_CPU1_P0P0_DP<16>
  AV11  VSS(704)  GROUND  = GND
  AV13  VSS(703)  GROUND  = GND
  AV15  TXT_PLTEN  IN  = PD_CPU1_TXT_PLTEN
  AV17  FRMAGENT  IN  = PU_CPU1_FRMAGENT
  AV19  VSS(702)  GROUND  = GND
  AV21  DEBUG_EN_N  BI  = CPU_XDP_PRESENT_N
  AV23  VSS(701)  GROUND  = GND
  AV25  VSS(700)  GROUND  = GND
  AV27  VCCIO(80)  POWER  = PVCCIO_CPU1
  AV59  VCCIN(233)  POWER  = PVCCIN_CPU1
  AV61  VCCIN(232)  POWER  = PVCCIN_CPU1
  AV63  VSS(699)  GROUND  = GND
  AV65  VSS(698)  GROUND  = GND
  AV67  VSS(697)  GROUND  = GND
  AV69  DDR2_ECC(2)  BI  = M_J_ECC<2>
  AV71  DDR2_DQS_DP(17)  BI  = M_J_DQS_DP<17>
  AV73  DDR2_ECC(4)  BI  = M_J_ECC<4>
  AV75  VSS(696)  GROUND  = GND
  AV77  RSVD(186)  BI  = TP_CPU1_RSVD_186
  AV79  DDR1_DQ(5)  BI  = M_H_DQ<5>
  AV81  DDR1_DQ(0)  BI  = M_H_DQ<0>
  AV83  VSS(695)  GROUND  = GND
  AV85  VCCINPMAX(1)  POWER  = VSENSE_VCCINR2PMAX_CPU1
  AW2  VSS(694)  GROUND  = GND
  AW4  UPI0_TX_DP(15)  OUT  = UPI_CPU1_CPU0_P0P0_DN<15>
  AW6  VCCIO(37)  POWER  = PVCCIO_CPU1
  AW8  UPI0_RX_DN(16)  IN  = UPI_CPU0_CPU1_P0P0_DN<16>
  AW10  VSS(693)  GROUND  = GND
